# BASEBOARD_FAB2 (Tioga Pass) — schematic netlist excerpt (pin names and nets, part order shuffled) for the footprints in the layout excerpt that follows; sources: Cadence DE-HDL packaged netlist, KiCad conversion of Wiwynn_Tioga_Pass_MB.brd

R1B13  RES  2.26K 1.0% CHIP  pkg 0402  page 226 : A = P3V3_STBY ; B = PWRGD_PVDDQ_KLM
C1G5  CAP  0.22UF 16V 10% X7R  pkg 0402  page 224 : A = P5V_STBY ; B = GND
R9A1  RES  1.00K 1% EMPTY  pkg 0402  page 111 : A = P3V3 ; B = XDP_CPU_TCK_BUF

(kicad_pcb
	(version 20260206)
	(generator "pcbnew")
	(generator_version "10.0")
	(general
		(thickness 1.6)
		(legacy_teardrops no)
	)
	(paper "A4")
	(title_block
		(title "Wiwynn_Tioga_Pass_MB.brd")
		(comment 1 "Tioga Pass / footprints 813-815 of 4770")
	)
	(layers
		(0 "F.Cu" signal "TOP")
		(4 "In1.Cu" signal "L2GND")
		(6 "In2.Cu" signal "L3")
		(8 "In3.Cu" signal "L4GND")
		(10 "In4.Cu" signal "L5")
		(12 "In5.Cu" signal "L6GND")
		(14 "In6.Cu" signal "L7VCC")
		(16 "In7.Cu" signal "L8VCC")
		(18 "In8.Cu" signal "L9GND")
		(20 "In9.Cu" signal "L10")
		(22 "In10.Cu" signal "L11GND")
		(24 "In11.Cu" signal "L12")
		(26 "In12.Cu" signal "L13GND")
		(2 "B.Cu" signal "BOTTOM")
		(9 "F.Adhes" user "F.Adhesive")
		(11 "B.Adhes" user "B.Adhesive")
		(13 "F.Paste" user "Package Geometry/Pastemask Top")
		(15 "B.Paste" user "Package Geometry/Pastemask Bottom")
		(5 "F.SilkS" user "Ref Des/Silkscreen Top")
		(7 "B.SilkS" user "Ref Des/Silkscreen Bottom")
		(1 "F.Mask" user "Board Geometry/Soldermask Top")
		(3 "B.Mask" user "Board Geometry/Soldermask Bottom")
		(17 "Dwgs.User" user "User.Drawings")
		(19 "Cmts.User" user "User.Comments")
		(21 "Eco1.User" user "User.Eco1")
		(23 "Eco2.User" user "User.Eco2")
		(25 "Edge.Cuts" user "Board Geometry/Outline")
		(27 "Margin" user)
		(31 "F.CrtYd" user "Package Geometry/Place Bound Top")
		(29 "B.CrtYd" user "Package Geometry/Place Bound Bottom")
		(35 "F.Fab" user "Ref Des/Assembly Top")
		(33 "B.Fab" user "Ref Des/Assembly Bottom")
	)
	(footprint ""
		(layer "F.Cu")
		(at -4.3688 -131.2672)
		(property "Reference" "R1B13"
			(at -0.8382 -0.67818 0)
			(unlocked yes)
			(layer "F.SilkS")
			(effects
				(font
					(size 0.4064 0.254)
					(thickness 0.1524)
				)
				(justify left)
			)
		)
		(property "Value" ""
			(at 0 0 0)
			(layer "F.Fab")
			(effects
				(font
					(size 1.27 1.27)
				)
			)
		)
		(duplicate_pad_numbers_are_jumpers no)
		(fp_poly
			(pts
				(xy -0.2794 -0.1016) (xy 0.2794 -0.1016) (xy 0.2794 0.9906) (xy -0.2794 0.9906)
			)
			(stroke
				(width 0)
				(type default)
			)
			(fill no)
			(layer "F.CrtYd")
		)
		(fp_line
			(start -0.2794 -0.1016)
			(end -0.2794 0.9906)
			(stroke
				(width 0.1)
				(type default)
			)
			(layer "F.Fab")
		)
		(fp_line
			(start -0.2794 0.9906)
			(end 0.2794 0.9906)
			(stroke
				(width 0.1)
				(type default)
			)
			(layer "F.Fab")
		)
		(fp_line
			(start 0.2794 -0.1016)
			(end -0.2794 -0.1016)
			(stroke
				(width 0.1)
				(type default)
			)
			(layer "F.Fab")
		)
		(fp_line
			(start 0.2794 0.9906)
			(end 0.2794 -0.1016)
			(stroke
				(width 0.1)
				(type default)
			)
			(layer "F.Fab")
		)
		(pad "1" smd rect
			(at 0 0)
			(size 0.508 0.508)
			(layers "F.Cu" "F.Mask" "F.Paste")
			(net "P3V3_STBY")
		)
		(pad "2" smd rect
			(at 0 0.889)
			(size 0.508 0.508)
			(layers "F.Cu" "F.Mask" "F.Paste")
			(net "PWRGD_PVDDQ_KLM")
		)
		(zone
			(layer "F.Cu")
			(hatch none 0.5)
			(connect_pads
				(clearance 0)
			)
			(min_thickness 0.25)
			(keepout
				(tracks allowed)
				(vias not_allowed)
				(pads allowed)
				(copperpour not_allowed)
				(footprints allowed)
			)
			(placement
				(enabled no)
				(sheetname "")
			)
			(fill
				(thermal_gap 0.5)
				(thermal_bridge_width 0.5)
				(island_removal_mode 0)
			)
			(polygon
				(pts
					(xy -4.6228 -131.0132) (xy -4.1148 -131.0132) (xy -4.1148 -130.6322) (xy -4.6228 -130.6322)
				)
			)
		)
		(zone
			(layer "F.Cu")
			(hatch none 0.5)
			(connect_pads
				(clearance 0)
			)
			(min_thickness 0.25)
			(keepout
				(tracks not_allowed)
				(vias allowed)
				(pads allowed)
				(copperpour not_allowed)
				(footprints allowed)
			)
			(placement
				(enabled no)
				(sheetname "")
			)
			(fill
				(thermal_gap 0.5)
				(thermal_bridge_width 0.5)
				(island_removal_mode 0)
			)
			(polygon
				(pts
					(xy -4.6228 -130.6322) (xy -4.1148 -130.6322) (xy -4.1148 -131.0132) (xy -4.6228 -131.0132)
				)
			)
		)
	)
	(footprint ""
		(layer "F.Cu")
		(at 4.2164 -5.675376 90)
		(property "Reference" "C1G5"
			(at 0 0 90)
			(layer "F.SilkS")
			(hide yes)
			(effects
				(font
					(size 1.27 1.27)
				)
			)
		)
		(property "Value" ""
			(at 0 0 90)
			(layer "F.Fab")
			(effects
				(font
					(size 1.27 1.27)
				)
			)
		)
		(duplicate_pad_numbers_are_jumpers no)
		(fp_rect
			(start 0.3048 0.9906)
			(end -0.3048 -0.1016)
			(stroke
				(width 0)
				(type default)
			)
			(fill no)
			(layer "F.CrtYd")
		)
		(fp_line
			(start 0.3048 -0.1016)
			(end -0.3048 -0.1016)
			(stroke
				(width 0.1)
				(type default)
			)
			(layer "F.Fab")
		)
		(fp_line
			(start -0.3048 -0.1016)
			(end -0.3048 0.9906)
			(stroke
				(width 0.1)
				(type default)
			)
			(layer "F.Fab")
		)
		(fp_line
			(start 0.3048 0.9906)
			(end 0.3048 -0.1016)
			(stroke
				(width 0.1)
				(type default)
			)
			(layer "F.Fab")
		)
		(fp_line
			(start -0.3048 0.9906)
			(end 0.3048 0.9906)
			(stroke
				(width 0.1)
				(type default)
			)
			(layer "F.Fab")
		)
		(pad "1" smd rect
			(at 0 0 90)
			(size 0.508 0.508)
			(layers "F.Cu" "F.Mask" "F.Paste")
			(net "P5V_STBY")
		)
		(pad "2" smd rect
			(at 0 0.889 90)
			(size 0.508 0.508)
			(layers "F.Cu" "F.Mask" "F.Paste")
			(net "GND")
		)
		(zone
			(layer "F.Cu")
			(hatch none 0.5)
			(connect_pads
				(clearance 0)
			)
			(min_thickness 0.25)
			(keepout
				(tracks not_allowed)
				(vias allowed)
				(pads allowed)
				(copperpour not_allowed)
				(footprints allowed)
			)
			(placement
				(enabled no)
				(sheetname "")
			)
			(fill
				(thermal_gap 0.5)
				(thermal_bridge_width 0.5)
				(island_removal_mode 0)
			)
			(polygon
				(pts
					(xy 4.8514 -5.929376) (xy 4.4704 -5.929376) (xy 4.4704 -5.421376) (xy 4.8514 -5.421376)
				)
			)
		)
		(zone
			(layer "F.Cu")
			(hatch none 0.5)
			(connect_pads
				(clearance 0)
			)
			(min_thickness 0.25)
			(keepout
				(tracks allowed)
				(vias not_allowed)
				(pads allowed)
				(copperpour not_allowed)
				(footprints allowed)
			)
			(placement
				(enabled no)
				(sheetname "")
			)
			(fill
				(thermal_gap 0.5)
				(thermal_bridge_width 0.5)
				(island_removal_mode 0)
			)
			(polygon
				(pts
					(xy 4.8514 -5.929376) (xy 4.4704 -5.929376) (xy 4.4704 -5.421376) (xy 4.8514 -5.421376)
				)
			)
		)
	)
	(footprint ""
		(layer "F.Cu")
		(at 452.12 -153.543 -90)
		(property "Reference" "R9A1"
			(at 0 0 270)
			(layer "F.SilkS")
			(hide yes)
			(effects
				(font
					(size 1.27 1.27)
				)
			)
		)
		(property "Value" ""
			(at 0 0 270)
			(layer "F.Fab")
			(effects
				(font
					(size 1.27 1.27)
				)
			)
		)
		(duplicate_pad_numbers_are_jumpers no)
		(fp_poly
			(pts
				(xy -0.2794 -0.1016) (xy 0.2794 -0.1016) (xy 0.2794 0.9906) (xy -0.2794 0.9906)
			)
			(stroke
				(width 0)
				(type default)
			)
			(fill no)
			(layer "F.CrtYd")
		)
		(fp_line
			(start -0.2794 0.9906)
			(end 0.2794 0.9906)
			(stroke
				(width 0.1)
				(type default)
			)
			(layer "F.Fab")
		)
		(fp_line
			(start 0.2794 0.9906)
			(end 0.2794 -0.1016)
			(stroke
				(width 0.1)
				(type default)
			)
			(layer "F.Fab")
		)
		(fp_line
			(start -0.2794 -0.1016)
			(end -0.2794 0.9906)
			(stroke
				(width 0.1)
				(type default)
			)
			(layer "F.Fab")
		)
		(fp_line
			(start 0.2794 -0.1016)
			(end -0.2794 -0.1016)
			(stroke
				(width 0.1)
				(type default)
			)
			(layer "F.Fab")
		)
		(pad "1" smd rect
			(at 0 0 270)
			(size 0.508 0.508)
			(layers "F.Cu" "F.Mask" "F.Paste")
			(net "P3V3")
		)
		(pad "2" smd rect
			(at 0 0.889 270)
			(size 0.508 0.508)
			(layers "F.Cu" "F.Mask" "F.Paste")
			(net "XDP_CPU_TCK_BUF")
		)
		(zone
			(layer "F.Cu")
			(hatch none 0.5)
			(connect_pads
				(clearance 0)
			)
			(min_thickness 0.25)
			(keepout
				(tracks not_allowed)
				(vias allowed)
				(pads allowed)
				(copperpour not_allowed)
				(footprints allowed)
			)
			(placement
				(enabled no)
				(sheetname "")
			)
			(fill
				(thermal_gap 0.5)
				(thermal_bridge_width 0.5)
				(island_removal_mode 0)
			)
			(polygon
				(pts
					(xy 451.485 -153.797) (xy 451.485 -153.289) (xy 451.866 -153.289) (xy 451.866 -153.797)
				)
			)
		)
		(zone
			(layer "F.Cu")
			(hatch none 0.5)
			(connect_pads
				(clearance 0)
			)
			(min_thickness 0.25)
			(keepout
				(tracks allowed)
				(vias not_allowed)
				(pads allowed)
				(copperpour not_allowed)
				(footprints allowed)
			)
			(placement
				(enabled no)
				(sheetname "")
			)
			(fill
				(thermal_gap 0.5)
				(thermal_bridge_width 0.5)
				(island_removal_mode 0)
			)
			(polygon
				(pts
					(xy 451.866 -153.797) (xy 451.866 -153.289) (xy 451.485 -153.289) (xy 451.485 -153.797)
				)
			)
		)
	)
)
